(kicad_pcb
	(version 20260206)
	(generator "pcbnew")
	(generator_version "10.0")
	(general
		(thickness 1.6)
		(legacy_teardrops no)
	)
	(paper "A4")
	(title_block
		(title "Wiwynn_Tioga_Pass_MB.brd")
		(comment 1 "Tioga Pass / footprints 2904-2911 of 4770")
	)
	(layers
		(0 "F.Cu" signal "TOP")
		(4 "In1.Cu" signal "L2GND")
		(6 "In2.Cu" signal "L3")
		(8 "In3.Cu" signal "L4GND")
		(10 "In4.Cu" signal "L5")
		(12 "In5.Cu" signal "L6GND")
		(14 "In6.Cu" signal "L7VCC")
		(16 "In7.Cu" signal "L8VCC")
		(18 "In8.Cu" signal "L9GND")
		(20 "In9.Cu" signal "L10")
		(22 "In10.Cu" signal "L11GND")
		(24 "In11.Cu" signal "L12")
		(26 "In12.Cu" signal "L13GND")
		(2 "B.Cu" signal "BOTTOM")
		(9 "F.Adhes" user "F.Adhesive")
		(11 "B.Adhes" user "B.Adhesive")
		(13 "F.Paste" user "Package Geometry/Pastemask Top")
		(15 "B.Paste" user "Package Geometry/Pastemask Bottom")
		(5 "F.SilkS" user "Ref Des/Silkscreen Top")
		(7 "B.SilkS" user "Ref Des/Silkscreen Bottom")
		(1 "F.Mask" user "Board Geometry/Soldermask Top")
		(3 "B.Mask" user "Board Geometry/Soldermask Bottom")
		(17 "Dwgs.User" user "User.Drawings")
		(19 "Cmts.User" user "User.Comments")
		(21 "Eco1.User" user "User.Eco1")
		(23 "Eco2.User" user "User.Eco2")
		(25 "Edge.Cuts" user "Board Geometry/Outline")
		(27 "Margin" user)
		(31 "F.CrtYd" user "Package Geometry/Place Bound Top")
		(29 "B.CrtYd" user "Package Geometry/Place Bound Bottom")
		(35 "F.Fab" user "Ref Des/Assembly Top")
		(33 "B.Fab" user "Ref Des/Assembly Bottom")
	)
	(footprint ""
		(layer "B.Cu")
		(at 438.6199 -141.097 180)
		(property "Reference" "R25W174"
			(at 0.8382 -0.67818 180)
			(unlocked yes)
			(layer "B.SilkS")
			(effects
				(font
					(size 0.4064 0.254)
					(thickness 0.1524)
				)
				(justify left mirror)
			)
		)
		(property "Value" ""
			(at 0 0 0)
			(layer "B.Fab")
			(effects
				(font
					(size 1.27 1.27)
				)
				(justify mirror)
			)
		)
		(duplicate_pad_numbers_are_jumpers no)
		(fp_poly
			(pts
				(xy 0.2794 -0.1016) (xy -0.2794 -0.1016) (xy -0.2794 0.9906) (xy 0.2794 0.9906)
			)
			(stroke
				(width 0)
				(type default)
			)
			(fill no)
			(layer "B.CrtYd")
		)
		(fp_line
			(start 0.2794 0.9906)
			(end -0.2794 0.9906)
			(stroke
				(width 0.1)
				(type default)
			)
			(layer "B.Fab")
		)
		(fp_line
			(start 0.2794 -0.1016)
			(end 0.2794 0.9906)
			(stroke
				(width 0.1)
				(type default)
			)
			(layer "B.Fab")
		)
		(fp_line
			(start -0.2794 0.9906)
			(end -0.2794 -0.1016)
			(stroke
				(width 0.1)
				(type default)
			)
			(layer "B.Fab")
		)
		(fp_line
			(start -0.2794 -0.1016)
			(end 0.2794 -0.1016)
			(stroke
				(width 0.1)
				(type default)
			)
			(layer "B.Fab")
		)
		(pad "1" smd rect
			(at 0 0)
			(size 0.508 0.508)
			(layers "B.Cu" "B.Mask" "B.Paste")
			(net "P3V3_STBY")
		)
		(pad "2" smd rect
			(at 0 0.889)
			(size 0.508 0.508)
			(layers "B.Cu" "B.Mask" "B.Paste")
			(net "BMC_JTAG_SEL_N")
		)
		(zone
			(layer "B.Cu")
			(hatch none 0.5)
			(connect_pads
				(clearance 0)
			)
			(min_thickness 0.25)
			(keepout
				(tracks not_allowed)
				(vias allowed)
				(pads allowed)
				(copperpour not_allowed)
				(footprints allowed)
			)
			(placement
				(enabled no)
				(sheetname "")
			)
			(fill
				(thermal_gap 0.5)
				(thermal_bridge_width 0.5)
				(island_removal_mode 0)
			)
			(polygon
				(pts
					(xy 438.3659 -141.732) (xy 438.8739 -141.732) (xy 438.8739 -141.351) (xy 438.3659 -141.351)
				)
			)
		)
		(zone
			(layer "B.Cu")
			(hatch none 0.5)
			(connect_pads
				(clearance 0)
			)
			(min_thickness 0.25)
			(keepout
				(tracks allowed)
				(vias not_allowed)
				(pads allowed)
				(copperpour not_allowed)
				(footprints allowed)
			)
			(placement
				(enabled no)
				(sheetname "")
			)
			(fill
				(thermal_gap 0.5)
				(thermal_bridge_width 0.5)
				(island_removal_mode 0)
			)
			(polygon
				(pts
					(xy 438.3659 -141.351) (xy 438.8739 -141.351) (xy 438.8739 -141.732) (xy 438.3659 -141.732)
				)
			)
		)
	)
	(footprint ""
		(layer "B.Cu")
		(at 8.0264 -132.3594)
		(property "Reference" "R9M3"
			(at 0 0 0)
			(layer "B.SilkS")
			(hide yes)
			(effects
				(font
					(size 1.27 1.27)
				)
				(justify mirror)
			)
		)
		(property "Value" ""
			(at 0 0 0)
			(layer "B.Fab")
			(effects
				(font
					(size 1.27 1.27)
				)
				(justify mirror)
			)
		)
		(duplicate_pad_numbers_are_jumpers no)
		(fp_rect
			(start -0.2794 0.9906)
			(end 0.2794 -0.1016)
			(stroke
				(width 0)
				(type default)
			)
			(fill no)
			(layer "B.CrtYd")
		)
		(fp_line
			(start -0.2794 -0.1016)
			(end 0.2794 -0.1016)
			(stroke
				(width 0.1)
				(type default)
			)
			(layer "B.Fab")
		)
		(fp_line
			(start -0.2794 0.9906)
			(end -0.2794 -0.1016)
			(stroke
				(width 0.1)
				(type default)
			)
			(layer "B.Fab")
		)
		(fp_line
			(start 0.2794 -0.1016)
			(end 0.2794 0.9906)
			(stroke
				(width 0.1)
				(type default)
			)
			(layer "B.Fab")
		)
		(fp_line
			(start 0.2794 0.9906)
			(end -0.2794 0.9906)
			(stroke
				(width 0.1)
				(type default)
			)
			(layer "B.Fab")
		)
		(pad "1" smd rect
			(at 0 0 180)
			(size 0.508 0.508)
			(layers "B.Cu" "B.Mask" "B.Paste")
			(net "P3V3_STBY")
		)
		(pad "2" smd rect
			(at 0 0.889 180)
			(size 0.508 0.508)
			(layers "B.Cu" "B.Mask" "B.Paste")
			(net "VR_PVDDQ_KLM_VDD")
		)
		(zone
			(layer "B.Cu")
			(hatch none 0.5)
			(connect_pads
				(clearance 0)
			)
			(min_thickness 0.25)
			(keepout
				(tracks not_allowed)
				(vias allowed)
				(pads allowed)
				(copperpour not_allowed)
				(footprints allowed)
			)
			(placement
				(enabled no)
				(sheetname "")
			)
			(fill
				(thermal_gap 0.5)
				(thermal_bridge_width 0.5)
				(island_removal_mode 0)
			)
			(polygon
				(pts
					(xy 7.7724 -131.7244) (xy 8.2804 -131.7244) (xy 8.2804 -132.1054) (xy 7.7724 -132.1054)
				)
			)
		)
		(zone
			(layer "B.Cu")
			(hatch none 0.5)
			(connect_pads
				(clearance 0)
			)
			(min_thickness 0.25)
			(keepout
				(tracks allowed)
				(vias not_allowed)
				(pads allowed)
				(copperpour not_allowed)
				(footprints allowed)
			)
			(placement
				(enabled no)
				(sheetname "")
			)
			(fill
				(thermal_gap 0.5)
				(thermal_bridge_width 0.5)
				(island_removal_mode 0)
			)
			(polygon
				(pts
					(xy 7.7724 -131.7244) (xy 8.2804 -131.7244) (xy 8.2804 -132.1054) (xy 7.7724 -132.1054)
				)
			)
		)
	)
	(footprint ""
		(layer "B.Cu")
		(at 396.216886 -16.438372 180)
		(property "Reference" "R32W6"
			(at 0.8382 -0.67818 180)
			(unlocked yes)
			(layer "B.SilkS")
			(effects
				(font
					(size 0.4064 0.254)
					(thickness 0.1524)
				)
				(justify left mirror)
			)
		)
		(property "Value" ""
			(at 0 0 0)
			(layer "B.Fab")
			(effects
				(font
					(size 1.27 1.27)
				)
				(justify mirror)
			)
		)
		(duplicate_pad_numbers_are_jumpers no)
		(fp_poly
			(pts
				(xy 0.2794 -0.1016) (xy -0.2794 -0.1016) (xy -0.2794 0.9906) (xy 0.2794 0.9906)
			)
			(stroke
				(width 0)
				(type default)
			)
			(fill no)
			(layer "B.CrtYd")
		)
		(fp_line
			(start 0.2794 0.9906)
			(end -0.2794 0.9906)
			(stroke
				(width 0.1)
				(type default)
			)
			(layer "B.Fab")
		)
		(fp_line
			(start 0.2794 -0.1016)
			(end 0.2794 0.9906)
			(stroke
				(width 0.1)
				(type default)
			)
			(layer "B.Fab")
		)
		(fp_line
			(start -0.2794 0.9906)
			(end -0.2794 -0.1016)
			(stroke
				(width 0.1)
				(type default)
			)
			(layer "B.Fab")
		)
		(fp_line
			(start -0.2794 -0.1016)
			(end 0.2794 -0.1016)
			(stroke
				(width 0.1)
				(type default)
			)
			(layer "B.Fab")
		)
		(pad "1" smd rect
			(at 0 0)
			(size 0.508 0.508)
			(layers "B.Cu" "B.Mask" "B.Paste")
			(net "P1V8_M2")
		)
		(pad "2" smd rect
			(at 0 0.889)
			(size 0.508 0.508)
			(layers "B.Cu" "B.Mask" "B.Paste")
			(net "SMB_M2_SDA")
		)
		(zone
			(layer "B.Cu")
			(hatch none 0.5)
			(connect_pads
				(clearance 0)
			)
			(min_thickness 0.25)
			(keepout
				(tracks not_allowed)
				(vias allowed)
				(pads allowed)
				(copperpour not_allowed)
				(footprints allowed)
			)
			(placement
				(enabled no)
				(sheetname "")
			)
			(fill
				(thermal_gap 0.5)
				(thermal_bridge_width 0.5)
				(island_removal_mode 0)
			)
			(polygon
				(pts
					(xy 395.962886 -17.073372) (xy 396.470886 -17.073372) (xy 396.470886 -16.692372) (xy 395.962886 -16.692372)
				)
			)
		)
		(zone
			(layer "B.Cu")
			(hatch none 0.5)
			(connect_pads
				(clearance 0)
			)
			(min_thickness 0.25)
			(keepout
				(tracks allowed)
				(vias not_allowed)
				(pads allowed)
				(copperpour not_allowed)
				(footprints allowed)
			)
			(placement
				(enabled no)
				(sheetname "")
			)
			(fill
				(thermal_gap 0.5)
				(thermal_bridge_width 0.5)
				(island_removal_mode 0)
			)
			(polygon
				(pts
					(xy 395.962886 -16.692372) (xy 396.470886 -16.692372) (xy 396.470886 -17.073372) (xy 395.962886 -17.073372)
				)
			)
		)
	)
	(footprint ""
		(layer "B.Cu")
		(at 104.902254 -79.60614 180)
		(property "Reference" "C8P9"
			(at 0 0 0)
			(layer "B.SilkS")
			(hide yes)
			(effects
				(font
					(size 1.27 1.27)
				)
				(justify mirror)
			)
		)
		(property "Value" ""
			(at 0 0 0)
			(layer "B.Fab")
			(effects
				(font
					(size 1.27 1.27)
				)
				(justify mirror)
			)
		)
		(duplicate_pad_numbers_are_jumpers no)
		(fp_poly
			(pts
				(xy 0.7239 -0.2159) (xy -0.7239 -0.2159) (xy -0.7239 1.9939) (xy 0.7239 1.9939)
			)
			(stroke
				(width 0)
				(type default)
			)
			(fill no)
			(layer "B.CrtYd")
		)
		(fp_line
			(start 0.7239 1.9939)
			(end -0.7239 1.9939)
			(stroke
				(width 0.1)
				(type default)
			)
			(layer "B.Fab")
		)
		(fp_line
			(start 0.7239 -0.2159)
			(end 0.7239 1.9939)
			(stroke
				(width 0.1)
				(type default)
			)
			(layer "B.Fab")
		)
		(fp_line
			(start -0.7239 1.9939)
			(end -0.7239 -0.2159)
			(stroke
				(width 0.1)
				(type default)
			)
			(layer "B.Fab")
		)
		(fp_line
			(start -0.7239 -0.2159)
			(end 0.7239 -0.2159)
			(stroke
				(width 0.1)
				(type default)
			)
			(layer "B.Fab")
		)
		(pad "1" smd rect
			(at 0 0)
			(size 1.27 1.016)
			(layers "B.Cu" "B.Mask" "B.Paste")
			(net "PVCCMCP_CPU1")
		)
		(pad "2" smd rect
			(at 0 1.778)
			(size 1.27 1.016)
			(layers "B.Cu" "B.Mask" "B.Paste")
			(net "GND")
		)
		(zone
			(layer "B.Cu")
			(hatch none 0.5)
			(connect_pads
				(clearance 0)
			)
			(min_thickness 0.25)
			(keepout
				(tracks not_allowed)
				(vias allowed)
				(pads allowed)
				(copperpour not_allowed)
				(footprints allowed)
			)
			(placement
				(enabled no)
				(sheetname "")
			)
			(fill
				(thermal_gap 0.5)
				(thermal_bridge_width 0.5)
				(island_removal_mode 0)
			)
			(polygon
				(pts
					(xy 104.267254 -80.11414) (xy 105.537254 -80.11414) (xy 105.537254 -80.87614) (xy 104.267254 -80.87614)
				)
			)
		)
	)
	(footprint ""
		(layer "B.Cu")
		(at 63.2968 -92.1512 90)
		(property "Reference" "R8N2"
			(at 0 0 90)
			(layer "B.SilkS")
			(hide yes)
			(effects
				(font
					(size 1.27 1.27)
				)
				(justify mirror)
			)
		)
		(property "Value" ""
			(at 0 0 90)
			(layer "B.Fab")
			(effects
				(font
					(size 1.27 1.27)
				)
				(justify mirror)
			)
		)
		(duplicate_pad_numbers_are_jumpers no)
		(fp_poly
			(pts
				(xy 0.2794 -0.1016) (xy -0.2794 -0.1016) (xy -0.2794 0.9906) (xy 0.2794 0.9906)
			)
			(stroke
				(width 0)
				(type default)
			)
			(fill no)
			(layer "B.CrtYd")
		)
		(fp_line
			(start 0.2794 -0.1016)
			(end 0.2794 0.9906)
			(stroke
				(width 0.1)
				(type default)
			)
			(layer "B.Fab")
		)
		(fp_line
			(start -0.2794 -0.1016)
			(end 0.2794 -0.1016)
			(stroke
				(width 0.1)
				(type default)
			)
			(layer "B.Fab")
		)
		(fp_line
			(start 0.2794 0.9906)
			(end -0.2794 0.9906)
			(stroke
				(width 0.1)
				(type default)
			)
			(layer "B.Fab")
		)
		(fp_line
			(start -0.2794 0.9906)
			(end -0.2794 -0.1016)
			(stroke
				(width 0.1)
				(type default)
			)
			(layer "B.Fab")
		)
		(pad "1" smd rect
			(at 0 0 270)
			(size 0.508 0.508)
			(layers "B.Cu" "B.Mask" "B.Paste")
			(net "P3V3_STBY")
		)
		(pad "2" smd rect
			(at 0 0.889 270)
			(size 0.508 0.508)
			(layers "B.Cu" "B.Mask" "B.Paste")
			(net "FM_CPU1_PKGID0")
		)
		(zone
			(layer "B.Cu")
			(hatch none 0.5)
			(connect_pads
				(clearance 0)
			)
			(min_thickness 0.25)
			(keepout
				(tracks allowed)
				(vias not_allowed)
				(pads allowed)
				(copperpour not_allowed)
				(footprints allowed)
			)
			(placement
				(enabled no)
				(sheetname "")
			)
			(fill
				(thermal_gap 0.5)
				(thermal_bridge_width 0.5)
				(island_removal_mode 0)
			)
			(polygon
				(pts
					(xy 63.5508 -92.4052) (xy 63.5508 -91.8972) (xy 63.9318 -91.8972) (xy 63.9318 -92.4052)
				)
			)
		)
		(zone
			(layer "B.Cu")
			(hatch none 0.5)
			(connect_pads
				(clearance 0)
			)
			(min_thickness 0.25)
			(keepout
				(tracks not_allowed)
				(vias allowed)
				(pads allowed)
				(copperpour not_allowed)
				(footprints allowed)
			)
			(placement
				(enabled no)
				(sheetname "")
			)
			(fill
				(thermal_gap 0.5)
				(thermal_bridge_width 0.5)
				(island_removal_mode 0)
			)
			(polygon
				(pts
					(xy 63.9318 -92.4052) (xy 63.9318 -91.8972) (xy 63.5508 -91.8972) (xy 63.5508 -92.4052)
				)
			)
		)
	)
	(footprint ""
		(layer "B.Cu")
		(at -3.102864 -11.551412 -90)
		(property "Reference" "C22W4"
			(at 0 0 90)
			(layer "B.SilkS")
			(hide yes)
			(effects
				(font
					(size 1.27 1.27)
				)
				(justify mirror)
			)
		)
		(property "Value" "*"
			(at 0.0762 -6.2357 270)
			(unlocked yes)
			(layer "B.Fab")
			(hide yes)
			(effects
				(font
					(size 1.27 1.016)
					(thickness 0.1524)
				)
				(justify mirror)
			)
		)
		(property "Device Type" "SC22U16V5MX-4-GP_SMD-BCG5-SC22A"
			(at 0.0762 -8.2677 270)
			(unlocked yes)
			(layer "B.Fab")
			(hide yes)
			(effects
				(font
					(size 1.27 1.016)
					(thickness 0.1524)
				)
				(justify mirror)
			)
		)
		(duplicate_pad_numbers_are_jumpers no)
		(fp_line
			(start -0.635 0)
			(end 0.635 0)
			(stroke
				(width 0.508)
				(type default)
			)
			(layer "B.SilkS")
		)
		(fp_rect
			(start 0.9652 1.778)
			(end -0.9652 -1.778)
			(stroke
				(width 0)
				(type default)
			)
			(fill no)
			(layer "B.CrtYd")
		)
		(fp_poly
			(pts
				(xy 0.9652 -1.778) (xy -0.9652 -1.778) (xy -0.9652 1.778) (xy 0.9652 1.778)
			)
			(stroke
				(width 0)
				(type default)
			)
			(fill no)
			(layer "B.Fab")
		)
		(pad "1" smd rect
			(at 0 -0.9652 90)
			(size 1.397 1.143)
			(layers "B.Cu" "B.Mask" "B.Paste")
			(net "VR_FET_SW_P12V_STBY_PVDDQ_GHJ")
		)
		(pad "2" smd rect
			(at 0 0.9652 90)
			(size 1.397 1.143)
			(layers "B.Cu" "B.Mask" "B.Paste")
			(net "GND")
		)
	)
	(footprint ""
		(layer "B.Cu")
		(at 422.656 -153.924 90)
		(property "Reference" "C2L6"
			(at 0 0 90)
			(layer "B.SilkS")
			(hide yes)
			(effects
				(font
					(size 1.27 1.27)
				)
				(justify mirror)
			)
		)
		(property "Value" ""
			(at 0 0 90)
			(layer "B.Fab")
			(effects
				(font
					(size 1.27 1.27)
				)
				(justify mirror)
			)
		)
		(duplicate_pad_numbers_are_jumpers no)
		(fp_poly
			(pts
				(xy -0.3048 -0.1016) (xy -0.3048 0.9906) (xy 0.3048 0.9906) (xy 0.3048 -0.1016)
			)
			(stroke
				(width 0)
				(type default)
			)
			(fill no)
			(layer "B.CrtYd")
		)
		(fp_line
			(start 0.3048 -0.1016)
			(end 0.3048 0.9906)
			(stroke
				(width 0.1)
				(type default)
			)
			(layer "B.Fab")
		)
		(fp_line
			(start -0.3048 -0.1016)
			(end 0.3048 -0.1016)
			(stroke
				(width 0.1)
				(type default)
			)
			(layer "B.Fab")
		)
		(fp_line
			(start 0.3048 0.9906)
			(end -0.3048 0.9906)
			(stroke
				(width 0.1)
				(type default)
			)
			(layer "B.Fab")
		)
		(fp_line
			(start -0.3048 0.9906)
			(end -0.3048 -0.1016)
			(stroke
				(width 0.1)
				(type default)
			)
			(layer "B.Fab")
		)
		(pad "1" smd rect
			(at 0 0 270)
			(size 0.508 0.508)
			(layers "B.Cu" "B.Mask" "B.Paste")
			(net "SATA6G_PCH_PCIE_UP_SATA_RXN<1>")
		)
		(pad "2" smd rect
			(at 0 0.889 270)
			(size 0.508 0.508)
			(layers "B.Cu" "B.Mask" "B.Paste")
			(net "SATA6G_P1_RX_C_DN")
		)
		(zone
			(layer "B.Cu")
			(hatch none 0.5)
			(connect_pads
				(clearance 0)
			)
			(min_thickness 0.25)
			(keepout
				(tracks allowed)
				(vias not_allowed)
				(pads allowed)
				(copperpour not_allowed)
				(footprints allowed)
			)
			(placement
				(enabled no)
				(sheetname "")
			)
			(fill
				(thermal_gap 0.5)
				(thermal_bridge_width 0.5)
				(island_removal_mode 0)
			)
			(polygon
				(pts
					(xy 422.91 -154.178) (xy 422.91 -153.67) (xy 423.291 -153.67) (xy 423.291 -154.178)
				)
			)
		)
		(zone
			(layer "B.Cu")
			(hatch none 0.5)
			(connect_pads
				(clearance 0)
			)
			(min_thickness 0.25)
			(keepout
				(tracks not_allowed)
				(vias allowed)
				(pads allowed)
				(copperpour not_allowed)
				(footprints allowed)
			)
			(placement
				(enabled no)
				(sheetname "")
			)
			(fill
				(thermal_gap 0.5)
				(thermal_bridge_width 0.5)
				(island_removal_mode 0)
			)
			(polygon
				(pts
					(xy 423.291 -154.178) (xy 423.291 -153.67) (xy 422.91 -153.67) (xy 422.91 -154.178)
				)
			)
		)
	)
	(footprint ""
		(layer "B.Cu")
		(at 452.5645 -19.177 -90)
		(property "Reference" "Q9W1"
			(at 0.229362 -1.2065 270)
			(unlocked yes)
			(layer "B.SilkS")
			(effects
				(font
					(size 0.4064 0.254)
					(thickness 0.1524)
				)
				(justify left mirror)
			)
		)
		(property "Value" ""
			(at 0 0 90)
			(layer "B.Fab")
			(effects
				(font
					(size 1.27 1.27)
				)
				(justify mirror)
			)
		)
		(duplicate_pad_numbers_are_jumpers no)
		(fp_line
			(start -1.778 2.4765)
			(end -1.778 1.5875)
			(stroke
				(width 0.1524)
				(type default)
			)
			(layer "B.SilkS")
		)
		(fp_line
			(start -0.9525 2.4765)
			(end -1.778 2.4765)
			(stroke
				(width 0.1524)
				(type default)
			)
			(layer "B.SilkS")
		)
		(fp_line
			(start -0.381 0.635)
			(end -0.381 1.27)
			(stroke
				(width 0.1524)
				(type default)
			)
			(layer "B.SilkS")
		)
		(fp_line
			(start -1.778 -0.5715)
			(end -1.778 0.3175)
			(stroke
				(width 0.1524)
				(type default)
			)
			(layer "B.SilkS")
		)
		(fp_line
			(start -0.9525 -0.5715)
			(end -1.778 -0.5715)
			(stroke
				(width 0.1524)
				(type default)
			)
			(layer "B.SilkS")
		)
		(fp_circle
			(center 0.9525 -0.9271)
			(end 0.9525 -1.0541)
			(stroke
				(width 0.254)
				(type default)
			)
			(fill no)
			(layer "B.SilkS")
		)
		(fp_poly
			(pts
				(xy -1.778 2.4765) (xy -0.381 2.4765) (xy -0.381 -0.5715) (xy -1.778 -0.5715)
			)
			(stroke
				(width 0)
				(type default)
			)
			(fill no)
			(layer "B.CrtYd")
		)
		(fp_line
			(start -1.778 2.4765)
			(end -1.778 -0.5715)
			(stroke
				(width 0.1)
				(type default)
			)
			(layer "B.Fab")
		)
		(fp_line
			(start -0.381 2.4765)
			(end -1.778 2.4765)
			(stroke
				(width 0.1)
				(type default)
			)
			(layer "B.Fab")
		)
		(fp_line
			(start -1.778 -0.5715)
			(end -0.381 -0.5715)
			(stroke
				(width 0.1)
				(type default)
			)
			(layer "B.Fab")
		)
		(fp_line
			(start -0.381 -0.5715)
			(end -0.381 2.4765)
			(stroke
				(width 0.1)
				(type default)
			)
			(layer "B.Fab")
		)
		(fp_circle
			(center 0.9525 -0.9271)
			(end 0.9525 -1.0541)
			(stroke
				(width 0.254)
				(type default)
			)
			(fill no)
			(layer "B.Fab")
		)
		(pad "1" smd rect
			(at 0 0 90)
			(size 1.143 0.508)
			(layers "B.Cu" "B.Mask" "B.Paste")
			(net "BMC_TPM_HW_C_RST")
		)
		(pad "2" smd rect
			(at 0 1.905 90)
			(size 1.143 0.508)
			(layers "B.Cu" "B.Mask" "B.Paste")
			(net "GND")
		)
		(pad "3" smd rect
			(at -2.159 0.9525 90)
			(size 1.143 0.508)
			(layers "B.Cu" "B.Mask" "B.Paste")
			(net "FM_TPM_PRES_RST_N")
		)
	)
)
